# T6G (Grand Teton) — schematic netlist excerpt (pin names and nets, part order shuffled) for the footprints in the layout excerpt that follows; sources: Cadence DE-HDL packaged netlist, KiCad conversion of 04192023_DAF0TMB3IC0_F0TG_MB_C_brd_V02_OCP.brd

J21  SCONN288_DDR506112002KQ  IO  pkg DDR288S_1-1VXC  page 90
  VIN_BULK0  = P12V_MEM_CPU0
  RFU0  = NC
  VIN_MGMT  = P3V3_AUX
  HSCL  = I3C_SPD_DDRE_CPU0_SCL
  HSDA  = I3C_SPD_DDRE_CPU0_SDA
  VSS0  = GND
  DQ0_A  = M_E_CPU0_SA_DQ<0>
  VSS1  = GND
  DQ1_A  = M_E_CPU0_SA_DQ<1>
  VSS2  = GND
  DQS0_A_T  = M_E_CPU0_SA_DQS_DP<0>
  DQS0_A_C  = M_E_CPU0_SA_DQS_DN<0>
  VSS3  = GND
  DQ4_A  = M_E_CPU0_SA_DQ<4>
  VSS4  = GND
  DQ5_A  = M_E_CPU0_SA_DQ<5>
  VSS5  = GND
  DQ8_A  = M_E_CPU0_SA_DQ<8>
  VSS6  = GND
  DQ9_A  = M_E_CPU0_SA_DQ<9>
  VSS7  = GND
  DQS1_A_T  = M_E_CPU0_SA_DQS_DP<1>
  DQS1_A_C  = M_E_CPU0_SA_DQS_DN<1>
  VSS8  = GND
  DQ12_A  = M_E_CPU0_SA_DQ<12>
  VSS9  = GND
  DQ13_A  = M_E_CPU0_SA_DQ<13>
  VSS10  = GND
  DQ16_A  = M_E_CPU0_SA_DQ<16>
  VSS11  = GND
  DQ17_A  = M_E_CPU0_SA_DQ<17>
  VSS12  = GND
  DQS2_A_T  = M_E_CPU0_SA_DQS_DP<2>
  DQS2_A_C  = M_E_CPU0_SA_DQS_DN<2>
  VSS13  = GND
  DQ20_A  = M_E_CPU0_SA_DQ<20>
  VSS14  = GND
  DQ21_A  = M_E_CPU0_SA_DQ<21>
  VSS15  = GND
  DQ24_A  = M_E_CPU0_SA_DQ<24>
  VSS16  = GND
  DQ25_A  = M_E_CPU0_SA_DQ<25>
  VSS17  = GND
  DQS3_A_T  = M_E_CPU0_SA_DQS_DP<3>
  DQS3_A_C  = M_E_CPU0_SA_DQS_DN<3>
  VSS18  = GND
  DQ28_A  = M_E_CPU0_SA_DQ<28>
  VSS19  = GND
  DQ29_A  = M_E_CPU0_SA_DQ<29>
  VSS20  = GND
  CB0_A  = M_E_CPU0_SA_CB<0>
  VSS21  = GND
  CB1_A  = M_E_CPU0_SA_CB<1>
  VSS22  = GND
  DQS4_A_T  = M_E_CPU0_SA_DQS_DP<4>
  DQS4_A_C  = M_E_CPU0_SA_DQS_DN<4>
  VSS23  = GND
  CB4_A  = M_E_CPU0_SA_CB<4>
  VSS24  = GND
  CB5_A  = M_E_CPU0_SA_CB<5>
  VSS25  = GND
  ALERT_N  = M_E_CPU0_ALERT_N
  VSS26  = GND
  CS0_A_N  = M_E_CPU0_SA_CS_N<0>
  VSS27  = GND
  CA0_A  = M_E_CPU0_SA_CA<0>
  VSS28  = GND
  CA2_A  = M_E_CPU0_SA_CA<2>
  VSS29  = GND
  CA4_A  = M_E_CPU0_SA_CA<4>
  VSS30  = GND
  CA6_A  = M_E_CPU0_SA_CA<6>
  VSS31  = GND
  PAR_A  = M_E_CPU0_SA_PAR
  VSS32  = GND
  CA0_B  = M_E_CPU0_SB_CA<0>
  VSS33  = GND
  CA2_B  = M_E_CPU0_SB_CA<2>
  VSS34  = GND
  CA4_B  = M_E_CPU0_SB_CA<4>
  VSS35  = GND
  CA6_B  = M_E_CPU0_SB_CA<6>
  VSS36  = GND
  CS0_B_N  = M_E_CPU0_SB_CS_N<0>
  VSS37  = GND
  \lbd||rsp_a_n\  = M_E_CPU0_SA_RSP<0>
  \lbs||rsp_b_n\  = M_E_CPU0_SB_RSP<0>
  VSS38  = GND
  CB4_B  = M_E_CPU0_SB_CB<4>
  VSS39  = GND
  CB5_B  = M_E_CPU0_SB_CB<5>
  VSS40  = GND
  \dqs9_b_t||tdqs9_b_t||dbi4_b_n\  = M_E_CPU0_SB_DQS_DP<9>
  \dqs9_b_c||tdqs9_b_c\  = M_E_CPU0_SB_DQS_DN<9>
  VSS41  = GND
  CB0_B  = M_E_CPU0_SB_CB<0>
  VSS42  = GND
  CB1_B  = M_E_CPU0_SB_CB<1>
  VSS43  = GND
  DQ0_B  = M_E_CPU0_SB_DQ<0>
  VSS44  = GND
  DQ1_B  = M_E_CPU0_SB_DQ<1>
  VSS45  = GND
  DQS0_B_T  = M_E_CPU0_SB_DQS_DP<0>
  DQS0_B_C  = M_E_CPU0_SB_DQS_DN<0>
  VSS46  = GND
  DQ4_B  = M_E_CPU0_SB_DQ<4>
  VSS47  = GND
  DQ5_B  = M_E_CPU0_SB_DQ<5>
  VSS48  = GND
  DQ8_B  = M_E_CPU0_SB_DQ<8>
  VSS49  = GND
  DQ9_B  = M_E_CPU0_SB_DQ<9>
  VSS50  = GND
  DQS1_B_T  = M_E_CPU0_SB_DQS_DP<1>
  DQS1_B_C  = M_E_CPU0_SB_DQS_DN<1>
  VSS51  = GND
  DQ12_B  = M_E_CPU0_SB_DQ<12>
  VSS52  = GND
  DQ13_B  = M_E_CPU0_SB_DQ<13>
  VSS53  = GND
  DQ16_B  = M_E_CPU0_SB_DQ<16>
  VSS54  = GND
  DQ17_B  = M_E_CPU0_SB_DQ<17>
  VSS55  = GND
  DQS2_B_T  = M_E_CPU0_SB_DQS_DP<2>
  DQS2_B_C  = M_E_CPU0_SB_DQS_DN<2>
  VSS56  = GND
  DQ20_B  = M_E_CPU0_SB_DQ<20>
  VSS57  = GND
  DQ21_B  = M_E_CPU0_SB_DQ<21>
  VSS58  = GND
  DQ24_B  = M_E_CPU0_SB_DQ<24>
  VSS59  = GND
  DQ25_B  = M_E_CPU0_SB_DQ<25>
  VSS60  = GND
  DQS3_B_T  = M_E_CPU0_SB_DQS_DP<3>
  DQS3_B_C  = M_E_CPU0_SB_DQS_DN<3>
  VSS61  = GND
  DQ28_B  = M_E_CPU0_SB_DQ<28>
  VSS62  = GND
  DQ29_B  = M_E_CPU0_SB_DQ<29>
  VSS63  = GND
  RFU1  = NC
  VIN_BULK1  = P12V_MEM_CPU0
  VIN_BULK2  = P12V_MEM_CPU0
  \pwr_good||fail_n\  = PWRGD_CHE_CPU0_DIMM
  HAS  = PD_CHE_CPU0_DIMM_SAA
  RFU2  = NC
  RFU3  = NC
  VSS64  = GND
  DQ2_A  = M_E_CPU0_SA_DQ<2>
  VSS65  = GND
  DQ3_A  = M_E_CPU0_SA_DQ<3>
  VSS66  = GND
  \dqs5_a_c||tdqs5_a_c||dqs5_a_t||tdqs5_a_t\  = M_E_CPU0_SA_DQS_DN<5>
  \dqs5_a_t||tdqs5_a_t\  = M_E_CPU0_SA_DQS_DP<5>
  VSS67  = GND
  DQ6_A  = M_E_CPU0_SA_DQ<6>
  VSS68  = GND
  DQ7_A  = M_E_CPU0_SA_DQ<7>
  VSS69  = GND
  DQ10_A  = M_E_CPU0_SA_DQ<10>
  VSS70  = GND
  DQ11_A  = M_E_CPU0_SA_DQ<11>
  VSS71  = GND
  \dqs6_a_c||tdqs6_a_c||dqs6_a_t||tdqs6_a_t\  = M_E_CPU0_SA_DQS_DN<6>
  \dqs6_a_t||tdqs6_a_t\  = M_E_CPU0_SA_DQS_DP<6>
  VSS72  = GND
  DQ14_A  = M_E_CPU0_SA_DQ<14>
  VSS73  = GND
  DQ15_A  = M_E_CPU0_SA_DQ<15>
  VSS74  = GND
  DQ18_A  = M_E_CPU0_SA_DQ<18>
  VSS75  = GND
  DQ19_A  = M_E_CPU0_SA_DQ<19>
  VSS76  = GND
  \dqs7_a_c||tdqs7_a_c\  = M_E_CPU0_SA_DQS_DN<7>
  \dqs7_a_t||tdqs7_a_t\  = M_E_CPU0_SA_DQS_DP<7>
  VSS77  = GND
  DQ22_A  = M_E_CPU0_SA_DQ<22>
  VSS78  = GND
  DQ23_A  = M_E_CPU0_SA_DQ<23>
  VSS79  = GND
  DQ26_A  = M_E_CPU0_SA_DQ<26>
  VSS80  = GND
  DQ27_A  = M_E_CPU0_SA_DQ<27>
  VSS81  = GND
  \dqs8_a_c||tdqs8_a_c\  = M_E_CPU0_SA_DQS_DN<8>
  \dqs8_a_t||tdqs8_a_t\  = M_E_CPU0_SA_DQS_DP<8>
  VSS82  = GND
  DQ30_A  = M_E_CPU0_SA_DQ<30>
  VSS83  = GND
  DQ31_A  = M_E_CPU0_SA_DQ<31>
  VSS84  = GND
  CB2_A  = M_E_CPU0_SA_CB<2>
  VSS85  = GND
  CB3_A  = M_E_CPU0_SA_CB<3>
  VSS86  = GND
  \dqs9_a_c||tdqs9_a_c\  = M_E_CPU0_SA_DQS_DN<9>
  \dqs9_a_t||tdqs9_a_t\  = M_E_CPU0_SA_DQS_DP<9>
  VSS87  = GND
  CB6_A  = M_E_CPU0_SA_CB<6>
  VSS88  = GND
  CB7_A  = M_E_CPU0_SA_CB<7>
  VSS89  = GND
  RESET_N  = M_E_CPU0_RESET_N
  VSS90  = GND
  CS1_A_N  = M_E_CPU0_SA_CS_N<1>
  VSS91  = GND
  CA1_A  = M_E_CPU0_SA_CA<1>
  VSS92  = GND
  CA3_A  = M_E_CPU0_SA_CA<3>
  VSS93  = GND
  CA5_A  = M_E_CPU0_SA_CA<5>
  VSS94  = GND
  CK_T  = M_E_CPU0_CLK_DP<0>
  CK_C  = M_E_CPU0_CLK_DN<0>
  VSS95  = GND
  RFU4  = NC
  CA1_B  = M_E_CPU0_SB_CA<1>
  VSS96  = GND
  CA3_B  = M_E_CPU0_SB_CA<3>
  VSS97  = GND
  CA5_B  = M_E_CPU0_SB_CA<5>
  VSS98  = GND
  PAR_B  = M_E_CPU0_SB_PAR
  VSS99  = GND
  CS1_B_N  = M_E_CPU0_SB_CS_N<1>
  VSS100  = GND
  RFU5  = NC
  RFU6  = NC
  VSS101  = GND
  CB6_B  = M_E_CPU0_SB_CB<6>
  VSS102  = GND
  CB7_B  = M_E_CPU0_SB_CB<7>
  VSS103  = GND
  DQS4_B_C  = M_E_CPU0_SB_DQS_DN<4>
  DQS4_B_T  = M_E_CPU0_SB_DQS_DP<4>
  VSS104  = GND
  CB2_B  = M_E_CPU0_SB_CB<2>
  VSS105  = GND
  CB3_B  = M_E_CPU0_SB_CB<3>
  VSS106  = GND
  DQ2_B  = M_E_CPU0_SB_DQ<2>
  VSS107  = GND
  DQ3_B  = M_E_CPU0_SB_DQ<3>
  VSS108  = GND
  \dqs5_b_c||tdqs5_b_c\  = M_E_CPU0_SB_DQS_DN<5>
  \dqs5_b_t||tdqs5_b_t\  = M_E_CPU0_SB_DQS_DP<5>
  VSS109  = GND
  DQ6_B  = M_E_CPU0_SB_DQ<6>
  VSS110  = GND
  DQ7_B  = M_E_CPU0_SB_DQ<7>
  VSS111  = GND
  DQ10_B  = M_E_CPU0_SB_DQ<10>
  VSS112  = GND
  DQ11_B  = M_E_CPU0_SB_DQ<11>
  VSS113  = GND
  \dqs6_b_c||tdqs6_b_c\  = M_E_CPU0_SB_DQS_DN<6>
  \dqs6_b_t||tdqs6_b_t\  = M_E_CPU0_SB_DQS_DP<6>
  VSS114  = GND
  DQ14_B  = M_E_CPU0_SB_DQ<14>
  VSS115  = GND
  DQ15_B  = M_E_CPU0_SB_DQ<15>
  VSS116  = GND
  DQ18_B  = M_E_CPU0_SB_DQ<18>
  VSS117  = GND
  DQ19_B  = M_E_CPU0_SB_DQ<19>
  VSS118  = GND
  \dqs7_b_c||tdqs7_b_c\  = M_E_CPU0_SB_DQS_DN<7>
  \dqs7_b_t||tdqs7_b_t\  = M_E_CPU0_SB_DQS_DP<7>
  VSS119  = GND
  DQ22_B  = M_E_CPU0_SB_DQ<22>
  VSS120  = GND
  DQ23_B  = M_E_CPU0_SB_DQ<23>
  VSS121  = GND
  DQ26_B  = M_E_CPU0_SB_DQ<26>
  VSS122  = GND
  DQ27_B  = M_E_CPU0_SB_DQ<27>
  VSS123  = GND
  \dqs8_b_c||tdqs8_b_c\  = M_E_CPU0_SB_DQS_DN<8>
  \dqs8_b_t||tdqs8_b_t\  = M_E_CPU0_SB_DQS_DP<8>
  VSS124  = GND
  DQ30_B  = M_E_CPU0_SB_DQ<30>
  VSS125  = GND
  DQ31_B  = M_E_CPU0_SB_DQ<31>
  VSS126  = GND
  G1  = GND
  G2  = GND
  G3  = GND

(kicad_pcb
	(version 20260206)
	(generator "pcbnew")
	(generator_version "10.0")
	(general
		(thickness 1.6)
		(legacy_teardrops no)
	)
	(paper "A4")
	(title_block
		(title "04192023_DAF0TMB3IC0_F0TG_MB_C_brd_V02_OCP.brd")
		(comment 1 "Grand Teton / footprint 3 of 8354 (J21), pads 277-291 of 291")
	)
	(layers
		(0 "F.Cu" signal "TOP")
		(4 "In1.Cu" signal "GND")
		(6 "In2.Cu" signal "IN1")
		(8 "In3.Cu" signal "GND1")
		(10 "In4.Cu" signal "IN2")
		(12 "In5.Cu" signal "GND2")
		(14 "In6.Cu" signal "IN3")
		(16 "In7.Cu" signal "GND3")
		(18 "In8.Cu" signal "VCC")
		(20 "In9.Cu" signal "VCC1")
		(22 "In10.Cu" signal "GND4")
		(24 "In11.Cu" signal "IN4")
		(26 "In12.Cu" signal "GND5")
		(28 "In13.Cu" signal "IN5")
		(30 "In14.Cu" signal "GND6")
		(32 "In15.Cu" signal "IN6")
		(34 "In16.Cu" signal "GND7")
		(2 "B.Cu" signal "BOTTOM")
		(9 "F.Adhes" user "F.Adhesive")
		(11 "B.Adhes" user "B.Adhesive")
		(13 "F.Paste" user "Package Geometry/Pastemask Top")
		(15 "B.Paste" user "Package Geometry/Pastemask Bottom")
		(5 "F.SilkS" user "Ref Des/Silkscreen Top")
		(7 "B.SilkS" user "Ref Des/Silkscreen Bottom")
		(1 "F.Mask" user "Board Geometry/Soldermask Top")
		(3 "B.Mask" user "Board Geometry/Soldermask Bottom")
		(17 "Dwgs.User" user "User.Drawings")
		(19 "Cmts.User" user "User.Comments")
		(21 "Eco1.User" user "User.Eco1")
		(23 "Eco2.User" user "User.Eco2")
		(25 "Edge.Cuts" user "Board Geometry/Outline")
		(27 "Margin" user)
		(31 "F.CrtYd" user "Package Geometry/Place Bound Top")
		(29 "B.CrtYd" user "Package Geometry/Place Bound Bottom")
		(35 "F.Fab" user "Ref Des/Assembly Top")
		(33 "B.Fab" user "Ref Des/Assembly Bottom")
	)
	(footprint ""
		(layer "F.Cu")
		(at 275.142198 -255.560068 180)
		(property "Reference" "J21"
			(at -2.2098 -81.984088 0)
			(unlocked yes)
			(layer "F.SilkS")
			(effects
				(font
					(size 0.7874 0.5842)
					(thickness 0.1524)
				)
			)
		)
		(property "Value" ""
			(at 0 0 180)
			(layer "F.Fab")
			(effects
				(font
					(size 1.27 1.27)
				)
			)
		)
		(duplicate_pad_numbers_are_jumpers no)
		(pad "277" smd rect
			(at 2.050034 53.975 90)
			(size 0.519938 1.4986)
			(layers "F.Cu" "F.Mask" "F.Paste")
			(net "GND")
		)
		(pad "278" smd rect
			(at 2.050034 54.824884 90)
			(size 0.519938 1.4986)
			(layers "F.Cu" "F.Mask" "F.Paste")
			(net "M_E_CPU0_SB_DQ<26>")
		)
		(pad "279" smd rect
			(at 2.050034 55.675022 90)
			(size 0.519938 1.4986)
			(layers "F.Cu" "F.Mask" "F.Paste")
			(net "GND")
		)
		(pad "280" smd rect
			(at 2.050034 56.524906 90)
			(size 0.519938 1.4986)
			(layers "F.Cu" "F.Mask" "F.Paste")
			(net "M_E_CPU0_SB_DQ<27>")
		)
		(pad "281" smd rect
			(at 2.050034 57.375044 90)
			(size 0.519938 1.4986)
			(layers "F.Cu" "F.Mask" "F.Paste")
			(net "GND")
		)
		(pad "282" smd rect
			(at 2.050034 58.224928 90)
			(size 0.519938 1.4986)
			(layers "F.Cu" "F.Mask" "F.Paste")
			(net "M_E_CPU0_SB_DQS_DN<8>")
		)
		(pad "283" smd rect
			(at 2.050034 59.075066 90)
			(size 0.519938 1.4986)
			(layers "F.Cu" "F.Mask" "F.Paste")
			(net "M_E_CPU0_SB_DQS_DP<8>")
		)
		(pad "284" smd rect
			(at 2.050034 59.92495 90)
			(size 0.519938 1.4986)
			(layers "F.Cu" "F.Mask" "F.Paste")
			(net "GND")
		)
		(pad "285" smd rect
			(at 2.050034 60.775088 90)
			(size 0.519938 1.4986)
			(layers "F.Cu" "F.Mask" "F.Paste")
			(net "M_E_CPU0_SB_DQ<30>")
		)
		(pad "286" smd rect
			(at 2.050034 61.624972 90)
			(size 0.519938 1.4986)
			(layers "F.Cu" "F.Mask" "F.Paste")
			(net "GND")
		)
		(pad "287" smd rect
			(at 2.050034 62.47511 90)
			(size 0.519938 1.4986)
			(layers "F.Cu" "F.Mask" "F.Paste")
			(net "M_E_CPU0_SB_DQ<31>")
		)
		(pad "288" smd rect
			(at 2.050034 63.324994 90)
			(size 0.519938 1.4986)
			(layers "F.Cu" "F.Mask" "F.Paste")
			(net "GND")
		)
		(pad "G1" thru_hole oval
			(at 0 -68.97497 90)
			(size 1.7272 3.4798)
			(drill oval 1.2192 2.4638)
			(layers "*.Cu" "*.Mask")
			(remove_unused_layers no)
			(net "GND")
			(clearance 0.127)
			(thermal_gap 0.127)
		)
		(pad "G2" thru_hole oval
			(at 0 3.875024 90)
			(size 1.7272 3.4798)
			(drill oval 1.2192 2.4638)
			(layers "*.Cu" "*.Mask")
			(remove_unused_layers no)
			(net "GND")
			(clearance 0.127)
			(thermal_gap 0.127)
		)
		(pad "G3" thru_hole oval
			(at 0 68.97497 90)
			(size 1.7272 3.4798)
			(drill oval 1.2192 2.4638)
			(layers "*.Cu" "*.Mask")
			(remove_unused_layers no)
			(net "GND")
			(clearance 0.127)
			(thermal_gap 0.127)
		)
	)
)
